(kicad_pcb
	(version 20260206)
	(generator "pcbnew")
	(generator_version "10.0")
	(general
		(thickness 1.6)
		(legacy_teardrops no)
	)
	(paper "A4")
	(title_block
		(title "04192023_DAF0TMB3IC0_F0TG_MB_C_brd_V02_OCP.brd")
		(comment 1 "Grand Teton / footprint 4641 of 8354 (U6012), pads 1-111 of 354")
	)
	(layers
		(0 "F.Cu" signal "TOP")
		(4 "In1.Cu" signal "GND")
		(6 "In2.Cu" signal "IN1")
		(8 "In3.Cu" signal "GND1")
		(10 "In4.Cu" signal "IN2")
		(12 "In5.Cu" signal "GND2")
		(14 "In6.Cu" signal "IN3")
		(16 "In7.Cu" signal "GND3")
		(18 "In8.Cu" signal "VCC")
		(20 "In9.Cu" signal "VCC1")
		(22 "In10.Cu" signal "GND4")
		(24 "In11.Cu" signal "IN4")
		(26 "In12.Cu" signal "GND5")
		(28 "In13.Cu" signal "IN5")
		(30 "In14.Cu" signal "GND6")
		(32 "In15.Cu" signal "IN6")
		(34 "In16.Cu" signal "GND7")
		(2 "B.Cu" signal "BOTTOM")
		(9 "F.Adhes" user "F.Adhesive")
		(11 "B.Adhes" user "B.Adhesive")
		(13 "F.Paste" user "Package Geometry/Pastemask Top")
		(15 "B.Paste" user "Package Geometry/Pastemask Bottom")
		(5 "F.SilkS" user "Ref Des/Silkscreen Top")
		(7 "B.SilkS" user "Ref Des/Silkscreen Bottom")
		(1 "F.Mask" user "Board Geometry/Soldermask Top")
		(3 "B.Mask" user "Board Geometry/Soldermask Bottom")
		(17 "Dwgs.User" user "User.Drawings")
		(19 "Cmts.User" user "User.Comments")
		(21 "Eco1.User" user "User.Eco1")
		(23 "Eco2.User" user "User.Eco2")
		(25 "Edge.Cuts" user "Board Geometry/Outline")
		(27 "Margin" user)
		(31 "F.CrtYd" user "Package Geometry/Place Bound Top")
		(29 "B.CrtYd" user "Package Geometry/Place Bound Bottom")
		(35 "F.Fab" user "Ref Des/Assembly Top")
		(33 "B.Fab" user "Ref Des/Assembly Bottom")
	)
	(footprint ""
		(layer "F.Cu")
		(at 412.095696 -395.724634)
		(property "Reference" "U6012"
			(at -8.00862 -7.649972 0)
			(unlocked yes)
			(layer "F.SilkS")
			(effects
				(font
					(size 0.7874 0.5842)
					(thickness 0.1524)
				)
				(justify left)
			)
		)
		(property "Value" ""
			(at 0 0 0)
			(layer "F.Fab")
			(effects
				(font
					(size 1.27 1.27)
				)
			)
		)
		(duplicate_pad_numbers_are_jumpers no)
		(pad "A1" smd oval
			(at 11.050016 -3.938524)
			(size 0.254 0.3302)
			(layers "F.Cu" "F.Mask" "F.Paste")
			(net "NCF_A1_CPU0_P2_GND")
		)
		(pad "A35" smd oval
			(at 11.050016 3.940048)
			(size 0.254 0.3302)
			(layers "F.Cu" "F.Mask" "F.Paste")
			(net "NCF_CPU0_P2_GND")
		)
		(pad "AA10" smd circle
			(at 7.602728 -1.431798)
			(size 0.381 0.381)
			(layers "F.Cu" "F.Mask" "F.Paste")
			(net "P5E_CPU0_P2_TX_BUF_DN<14>")
		)
		(pad "AA29" smd circle
			(at 7.602728 2.032254)
			(size 0.381 0.381)
			(layers "F.Cu" "F.Mask" "F.Paste")
			(net "P5E_CPU0_P2_RX_DN<14>")
		)
		(pad "AB1" smd oval
			(at 7.450074 -3.938524)
			(size 0.254 0.3302)
			(layers "F.Cu" "F.Mask" "F.Paste")
			(net "P5E_CPU0_P2_RX_BUF_DP<14>")
		)
		(pad "AB35" smd oval
			(at 7.450074 3.940048)
			(size 0.254 0.3302)
			(layers "F.Cu" "F.Mask" "F.Paste")
			(net "P5E_CPU0_P2_TX_C_DP<14>")
		)
		(pad "AC4" smd circle
			(at 7.202678 -2.817368)
			(size 0.381 0.381)
			(layers "F.Cu" "F.Mask" "F.Paste")
			(net "GND")
		)
		(pad "AC13" smd circle
			(at 7.202678 -0.79629)
			(size 0.3048 0.3048)
			(layers "F.Cu" "F.Mask" "F.Paste")
			(net "GND")
		)
		(pad "AC17" smd circle
			(at 7.202678 -0.296164)
			(size 0.3048 0.3048)
			(layers "F.Cu" "F.Mask" "F.Paste")
			(net "P0V9_CPU0_RT2_2A")
		)
		(pad "AC20" smd circle
			(at 7.202678 0.203708)
			(size 0.3048 0.3048)
			(layers "F.Cu" "F.Mask" "F.Paste")
			(net "P0V9_CPU0_RT2_2A")
		)
		(pad "AC22" smd circle
			(at 7.202678 0.703834)
			(size 0.3048 0.3048)
			(layers "F.Cu" "F.Mask" "F.Paste")
			(net "GND")
		)
		(pad "AC32" smd circle
			(at 7.202678 2.724912)
			(size 0.381 0.381)
			(layers "F.Cu" "F.Mask" "F.Paste")
			(net "GND")
		)
		(pad "AD2" smd circle
			(at 7.1501 -3.41884)
			(size 0.3048 0.3048)
			(layers "F.Cu" "F.Mask" "F.Paste")
			(net "GND")
		)
		(pad "AD34" smd circle
			(at 7.1501 3.420364)
			(size 0.3048 0.3048)
			(layers "F.Cu" "F.Mask" "F.Paste")
			(net "GND")
		)
		(pad "AE1" smd oval
			(at 6.849872 -3.938524)
			(size 0.254 0.3302)
			(layers "F.Cu" "F.Mask" "F.Paste")
			(net "GND")
		)
		(pad "AE35" smd oval
			(at 6.849872 3.940048)
			(size 0.254 0.3302)
			(layers "F.Cu" "F.Mask" "F.Paste")
			(net "GND")
		)
		(pad "AF7" smd circle
			(at 6.802628 -2.12471)
			(size 0.381 0.381)
			(layers "F.Cu" "F.Mask" "F.Paste")
			(net "P5E_CPU0_P2_TX_BUF_DP<13>")
		)
		(pad "AF26" smd circle
			(at 6.802628 1.339342)
			(size 0.381 0.381)
			(layers "F.Cu" "F.Mask" "F.Paste")
			(net "P5E_CPU0_P2_RX_DP<13>")
		)
		(pad "AG2" smd circle
			(at 6.549898 -3.41884)
			(size 0.3048 0.3048)
			(layers "F.Cu" "F.Mask" "F.Paste")
			(net "P5E_CPU0_P2_RX_BUF_DN<13>")
		)
		(pad "AG34" smd circle
			(at 6.549898 3.420364)
			(size 0.3048 0.3048)
			(layers "F.Cu" "F.Mask" "F.Paste")
			(net "P5E_CPU0_P2_TX_C_DN<13>")
		)
		(pad "AH10" smd circle
			(at 6.402578 -1.431798)
			(size 0.381 0.381)
			(layers "F.Cu" "F.Mask" "F.Paste")
			(net "P5E_CPU0_P2_TX_BUF_DN<13>")
		)
		(pad "AH29" smd circle
			(at 6.402578 2.032254)
			(size 0.381 0.381)
			(layers "F.Cu" "F.Mask" "F.Paste")
			(net "P5E_CPU0_P2_RX_DN<13>")
		)
		(pad "AJ1" smd oval
			(at 6.249924 -3.938524)
			(size 0.254 0.3302)
			(layers "F.Cu" "F.Mask" "F.Paste")
			(net "P5E_CPU0_P2_RX_BUF_DP<13>")
		)
		(pad "AJ35" smd oval
			(at 6.249924 3.940048)
			(size 0.254 0.3302)
			(layers "F.Cu" "F.Mask" "F.Paste")
			(net "P5E_CPU0_P2_TX_C_DP<13>")
		)
		(pad "AK4" smd circle
			(at 6.002528 -2.817368)
			(size 0.381 0.381)
			(layers "F.Cu" "F.Mask" "F.Paste")
			(net "GND")
		)
		(pad "AK13" smd circle
			(at 6.002528 -0.79629)
			(size 0.3048 0.3048)
			(layers "F.Cu" "F.Mask" "F.Paste")
			(net "GND")
		)
		(pad "AK17" smd circle
			(at 6.002528 -0.296164)
			(size 0.3048 0.3048)
			(layers "F.Cu" "F.Mask" "F.Paste")
			(net "P0V9_CPU0_RT2_2A")
		)
		(pad "AK20" smd circle
			(at 6.002528 0.203708)
			(size 0.3048 0.3048)
			(layers "F.Cu" "F.Mask" "F.Paste")
			(net "P0V9_CPU0_RT2_2A")
		)
		(pad "AK22" smd circle
			(at 6.002528 0.703834)
			(size 0.3048 0.3048)
			(layers "F.Cu" "F.Mask" "F.Paste")
			(net "GND")
		)
		(pad "AK32" smd circle
			(at 6.002528 2.724912)
			(size 0.381 0.381)
			(layers "F.Cu" "F.Mask" "F.Paste")
			(net "GND")
		)
		(pad "AL2" smd circle
			(at 5.94995 -3.41884)
			(size 0.3048 0.3048)
			(layers "F.Cu" "F.Mask" "F.Paste")
			(net "GND")
		)
		(pad "AL34" smd circle
			(at 5.94995 3.420364)
			(size 0.3048 0.3048)
			(layers "F.Cu" "F.Mask" "F.Paste")
			(net "GND")
		)
		(pad "AM1" smd oval
			(at 5.649976 -3.938524)
			(size 0.254 0.3302)
			(layers "F.Cu" "F.Mask" "F.Paste")
			(net "GND")
		)
		(pad "AM35" smd oval
			(at 5.649976 3.940048)
			(size 0.254 0.3302)
			(layers "F.Cu" "F.Mask" "F.Paste")
			(net "GND")
		)
		(pad "AN7" smd circle
			(at 5.602478 -2.12471)
			(size 0.381 0.381)
			(layers "F.Cu" "F.Mask" "F.Paste")
			(net "P5E_CPU0_P2_TX_BUF_DP<12>")
		)
		(pad "AN26" smd circle
			(at 5.602478 1.339342)
			(size 0.381 0.381)
			(layers "F.Cu" "F.Mask" "F.Paste")
			(net "P5E_CPU0_P2_RX_DP<12>")
		)
		(pad "AP2" smd circle
			(at 5.350002 -3.41884)
			(size 0.3048 0.3048)
			(layers "F.Cu" "F.Mask" "F.Paste")
			(net "P5E_CPU0_P2_RX_BUF_DN<12>")
		)
		(pad "AP34" smd circle
			(at 5.350002 3.420364)
			(size 0.3048 0.3048)
			(layers "F.Cu" "F.Mask" "F.Paste")
			(net "P5E_CPU0_P2_TX_C_DN<12>")
		)
		(pad "AR10" smd circle
			(at 5.202682 -1.431798)
			(size 0.381 0.381)
			(layers "F.Cu" "F.Mask" "F.Paste")
			(net "P5E_CPU0_P2_TX_BUF_DN<12>")
		)
		(pad "AR29" smd circle
			(at 5.202682 2.032254)
			(size 0.381 0.381)
			(layers "F.Cu" "F.Mask" "F.Paste")
			(net "P5E_CPU0_P2_RX_DN<12>")
		)
		(pad "AT1" smd oval
			(at 5.050028 -3.938524)
			(size 0.254 0.3302)
			(layers "F.Cu" "F.Mask" "F.Paste")
			(net "P5E_CPU0_P2_RX_BUF_DP<12>")
		)
		(pad "AT35" smd oval
			(at 5.050028 3.940048)
			(size 0.254 0.3302)
			(layers "F.Cu" "F.Mask" "F.Paste")
			(net "P5E_CPU0_P2_TX_C_DP<12>")
		)
		(pad "AU4" smd circle
			(at 4.802632 -2.817368)
			(size 0.381 0.381)
			(layers "F.Cu" "F.Mask" "F.Paste")
			(net "GND")
		)
		(pad "AU13" smd circle
			(at 4.802632 -0.79629)
			(size 0.3048 0.3048)
			(layers "F.Cu" "F.Mask" "F.Paste")
			(net "GND")
		)
		(pad "AU17" smd circle
			(at 4.802632 -0.296164)
			(size 0.3048 0.3048)
			(layers "F.Cu" "F.Mask" "F.Paste")
			(net "P0V9_CPU0_RT2_2A")
		)
		(pad "AU20" smd circle
			(at 4.802632 0.203708)
			(size 0.3048 0.3048)
			(layers "F.Cu" "F.Mask" "F.Paste")
			(net "P0V9_CPU0_RT2_2A")
		)
		(pad "AU22" smd circle
			(at 4.802632 0.703834)
			(size 0.3048 0.3048)
			(layers "F.Cu" "F.Mask" "F.Paste")
			(net "GND")
		)
		(pad "AU32" smd circle
			(at 4.802632 2.724912)
			(size 0.381 0.381)
			(layers "F.Cu" "F.Mask" "F.Paste")
			(net "GND")
		)
		(pad "AV2" smd circle
			(at 4.750054 -3.41884)
			(size 0.3048 0.3048)
			(layers "F.Cu" "F.Mask" "F.Paste")
			(net "GND")
		)
		(pad "AV34" smd circle
			(at 4.750054 3.420364)
			(size 0.3048 0.3048)
			(layers "F.Cu" "F.Mask" "F.Paste")
			(net "GND")
		)
		(pad "AW1" smd oval
			(at 4.45008 -3.938524)
			(size 0.254 0.3302)
			(layers "F.Cu" "F.Mask" "F.Paste")
			(net "GND")
		)
		(pad "AW35" smd oval
			(at 4.45008 3.940048)
			(size 0.254 0.3302)
			(layers "F.Cu" "F.Mask" "F.Paste")
			(net "GND")
		)
		(pad "AY7" smd circle
			(at 4.402582 -2.12471)
			(size 0.381 0.381)
			(layers "F.Cu" "F.Mask" "F.Paste")
			(net "P5E_CPU0_P2_TX_BUF_DP<11>")
		)
		(pad "AY26" smd circle
			(at 4.402582 1.339342)
			(size 0.381 0.381)
			(layers "F.Cu" "F.Mask" "F.Paste")
			(net "P5E_CPU0_P2_RX_DP<11>")
		)
		(pad "B3" smd oval
			(at 10.885932 -2.888488 90)
			(size 0.254 0.3302)
			(layers "F.Cu" "F.Mask" "F.Paste")
			(net "JTAG_TCK_RT_CPU0_P2")
		)
		(pad "B6" smd oval
			(at 10.885932 -2.288286 90)
			(size 0.254 0.3302)
			(layers "F.Cu" "F.Mask" "F.Paste")
			(net "JTAG_TDI_RT_CPU0_P2")
		)
		(pad "B9" smd oval
			(at 10.885932 -1.688338 90)
			(size 0.254 0.3302)
			(layers "F.Cu" "F.Mask" "F.Paste")
			(net "JTAG_TDO_RT_CPU0_P2")
		)
		(pad "B12" smd oval
			(at 10.885932 -1.08839 90)
			(size 0.254 0.3302)
			(layers "F.Cu" "F.Mask" "F.Paste")
			(net "JTAG_TMS_RT_CPU0_P2")
		)
		(pad "B16" smd oval
			(at 10.885932 -0.488442 90)
			(size 0.254 0.3302)
			(layers "F.Cu" "F.Mask" "F.Paste")
			(net "Net_2211")
		)
		(pad "B19" smd oval
			(at 10.885932 0.111506 90)
			(size 0.254 0.3302)
			(layers "F.Cu" "F.Mask" "F.Paste")
			(net "GND")
		)
		(pad "B23" smd oval
			(at 10.885932 0.711708 90)
			(size 0.254 0.3302)
			(layers "F.Cu" "F.Mask" "F.Paste")
			(net "RT_CPU0_P2_ADDR2")
		)
		(pad "B25" smd oval
			(at 10.885932 1.311656 90)
			(size 0.254 0.3302)
			(layers "F.Cu" "F.Mask" "F.Paste")
			(net "RT_CPU0_P2_ADDR3")
		)
		(pad "B28" smd oval
			(at 10.885932 1.911604 90)
			(size 0.254 0.3302)
			(layers "F.Cu" "F.Mask" "F.Paste")
			(net "SMB_RT_CPU0_P2_R2_SDA")
		)
		(pad "B31" smd oval
			(at 10.885932 2.511552 90)
			(size 0.254 0.3302)
			(layers "F.Cu" "F.Mask" "F.Paste")
			(net "SMB_RT_CPU0_P2_R2_SCL")
		)
		(pad "BA2" smd circle
			(at 4.150106 -3.41884)
			(size 0.3048 0.3048)
			(layers "F.Cu" "F.Mask" "F.Paste")
			(net "P5E_CPU0_P2_RX_BUF_DN<11>")
		)
		(pad "BA34" smd circle
			(at 4.150106 3.420364)
			(size 0.3048 0.3048)
			(layers "F.Cu" "F.Mask" "F.Paste")
			(net "P5E_CPU0_P2_TX_C_DN<11>")
		)
		(pad "BB10" smd circle
			(at 4.002532 -1.431798)
			(size 0.381 0.381)
			(layers "F.Cu" "F.Mask" "F.Paste")
			(net "P5E_CPU0_P2_TX_BUF_DN<11>")
		)
		(pad "BB29" smd circle
			(at 4.002532 2.032254)
			(size 0.381 0.381)
			(layers "F.Cu" "F.Mask" "F.Paste")
			(net "P5E_CPU0_P2_RX_DN<11>")
		)
		(pad "BC1" smd oval
			(at 3.849878 -3.938524)
			(size 0.254 0.3302)
			(layers "F.Cu" "F.Mask" "F.Paste")
			(net "P5E_CPU0_P2_RX_BUF_DP<11>")
		)
		(pad "BC35" smd oval
			(at 3.849878 3.940048)
			(size 0.254 0.3302)
			(layers "F.Cu" "F.Mask" "F.Paste")
			(net "P5E_CPU0_P2_TX_C_DP<11>")
		)
		(pad "BD4" smd circle
			(at 3.602482 -2.817368)
			(size 0.381 0.381)
			(layers "F.Cu" "F.Mask" "F.Paste")
			(net "GND")
		)
		(pad "BD13" smd circle
			(at 3.602482 -0.79629)
			(size 0.3048 0.3048)
			(layers "F.Cu" "F.Mask" "F.Paste")
			(net "GND")
		)
		(pad "BD17" smd circle
			(at 3.602482 -0.296164)
			(size 0.3048 0.3048)
			(layers "F.Cu" "F.Mask" "F.Paste")
			(net "P0V9_CPU0_RT2_2A_2D")
		)
		(pad "BD20" smd circle
			(at 3.602482 0.203708)
			(size 0.3048 0.3048)
			(layers "F.Cu" "F.Mask" "F.Paste")
			(net "P0V9_CPU0_RT2_2A_2D")
		)
		(pad "BD22" smd circle
			(at 3.602482 0.703834)
			(size 0.3048 0.3048)
			(layers "F.Cu" "F.Mask" "F.Paste")
			(net "GND")
		)
		(pad "BD32" smd circle
			(at 3.602482 2.724912)
			(size 0.381 0.381)
			(layers "F.Cu" "F.Mask" "F.Paste")
			(net "GND")
		)
		(pad "BE2" smd circle
			(at 3.549904 -3.41884)
			(size 0.3048 0.3048)
			(layers "F.Cu" "F.Mask" "F.Paste")
			(net "GND")
		)
		(pad "BE34" smd circle
			(at 3.549904 3.420364)
			(size 0.3048 0.3048)
			(layers "F.Cu" "F.Mask" "F.Paste")
			(net "GND")
		)
		(pad "BF1" smd oval
			(at 3.24993 -3.938524)
			(size 0.254 0.3302)
			(layers "F.Cu" "F.Mask" "F.Paste")
			(net "GND")
		)
		(pad "BF35" smd oval
			(at 3.24993 3.940048)
			(size 0.254 0.3302)
			(layers "F.Cu" "F.Mask" "F.Paste")
			(net "GND")
		)
		(pad "BG7" smd circle
			(at 3.202686 -2.12471)
			(size 0.381 0.381)
			(layers "F.Cu" "F.Mask" "F.Paste")
			(net "P5E_CPU0_P2_TX_BUF_DP<10>")
		)
		(pad "BG26" smd circle
			(at 3.202686 1.339342)
			(size 0.381 0.381)
			(layers "F.Cu" "F.Mask" "F.Paste")
			(net "P5E_CPU0_P2_RX_DP<10>")
		)
		(pad "BH2" smd circle
			(at 2.949956 -3.41884)
			(size 0.3048 0.3048)
			(layers "F.Cu" "F.Mask" "F.Paste")
			(net "P5E_CPU0_P2_RX_BUF_DN<10>")
		)
		(pad "BH34" smd circle
			(at 2.949956 3.420364)
			(size 0.3048 0.3048)
			(layers "F.Cu" "F.Mask" "F.Paste")
			(net "P5E_CPU0_P2_TX_C_DN<10>")
		)
		(pad "BJ10" smd circle
			(at 2.802636 -1.431798)
			(size 0.381 0.381)
			(layers "F.Cu" "F.Mask" "F.Paste")
			(net "P5E_CPU0_P2_TX_BUF_DN<10>")
		)
		(pad "BJ29" smd circle
			(at 2.802636 2.032254)
			(size 0.381 0.381)
			(layers "F.Cu" "F.Mask" "F.Paste")
			(net "P5E_CPU0_P2_RX_DN<10>")
		)
		(pad "BK1" smd oval
			(at 2.649982 -3.938524)
			(size 0.254 0.3302)
			(layers "F.Cu" "F.Mask" "F.Paste")
			(net "P5E_CPU0_P2_RX_BUF_DP<10>")
		)
		(pad "BK35" smd oval
			(at 2.649982 3.940048)
			(size 0.254 0.3302)
			(layers "F.Cu" "F.Mask" "F.Paste")
			(net "P5E_CPU0_P2_TX_C_DP<10>")
		)
		(pad "BL4" smd circle
			(at 2.402586 -2.817368)
			(size 0.381 0.381)
			(layers "F.Cu" "F.Mask" "F.Paste")
			(net "GND")
		)
		(pad "BL13" smd circle
			(at 2.402586 -0.79629)
			(size 0.3048 0.3048)
			(layers "F.Cu" "F.Mask" "F.Paste")
			(net "GND")
		)
		(pad "BL17" smd circle
			(at 2.402586 -0.296164)
			(size 0.3048 0.3048)
			(layers "F.Cu" "F.Mask" "F.Paste")
			(net "P0V9_CPU0_RT_2D")
		)
		(pad "BL20" smd circle
			(at 2.402586 0.203708)
			(size 0.3048 0.3048)
			(layers "F.Cu" "F.Mask" "F.Paste")
			(net "P0V9_CPU0_RT_2D")
		)
		(pad "BL22" smd circle
			(at 2.402586 0.703834)
			(size 0.3048 0.3048)
			(layers "F.Cu" "F.Mask" "F.Paste")
			(net "GND")
		)
		(pad "BL32" smd circle
			(at 2.402586 2.724912)
			(size 0.381 0.381)
			(layers "F.Cu" "F.Mask" "F.Paste")
			(net "GND")
		)
		(pad "BM2" smd circle
			(at 2.350008 -3.41884)
			(size 0.3048 0.3048)
			(layers "F.Cu" "F.Mask" "F.Paste")
			(net "GND")
		)
		(pad "BM34" smd circle
			(at 2.350008 3.420364)
			(size 0.3048 0.3048)
			(layers "F.Cu" "F.Mask" "F.Paste")
			(net "GND")
		)
		(pad "BN1" smd oval
			(at 2.050034 -3.938524)
			(size 0.254 0.3302)
			(layers "F.Cu" "F.Mask" "F.Paste")
			(net "GND")
		)
		(pad "BN35" smd oval
			(at 2.050034 3.940048)
			(size 0.254 0.3302)
			(layers "F.Cu" "F.Mask" "F.Paste")
			(net "GND")
		)
		(pad "BP7" smd circle
			(at 2.002536 -2.12471)
			(size 0.381 0.381)
			(layers "F.Cu" "F.Mask" "F.Paste")
			(net "P5E_CPU0_P2_TX_BUF_DP<9>")
		)
		(pad "BP26" smd circle
			(at 2.002536 1.339342)
			(size 0.381 0.381)
			(layers "F.Cu" "F.Mask" "F.Paste")
			(net "P5E_CPU0_P2_RX_DP<9>")
		)
		(pad "BR2" smd circle
			(at 1.75006 -3.41884)
			(size 0.3048 0.3048)
			(layers "F.Cu" "F.Mask" "F.Paste")
			(net "P5E_CPU0_P2_RX_BUF_DN<9>")
		)
		(pad "BR34" smd circle
			(at 1.75006 3.420364)
			(size 0.3048 0.3048)
			(layers "F.Cu" "F.Mask" "F.Paste")
			(net "P5E_CPU0_P2_TX_C_DN<9>")
		)
		(pad "BT10" smd circle
			(at 1.602486 -1.431798)
			(size 0.381 0.381)
			(layers "F.Cu" "F.Mask" "F.Paste")
			(net "P5E_CPU0_P2_TX_BUF_DN<9>")
		)
		(pad "BT29" smd circle
			(at 1.602486 2.032254)
			(size 0.381 0.381)
			(layers "F.Cu" "F.Mask" "F.Paste")
			(net "P5E_CPU0_P2_RX_DN<9>")
		)
		(pad "BU1" smd oval
			(at 1.450086 -3.938524)
			(size 0.254 0.3302)
			(layers "F.Cu" "F.Mask" "F.Paste")
			(net "P5E_CPU0_P2_RX_BUF_DP<9>")
		)
		(pad "BU35" smd oval
			(at 1.450086 3.940048)
			(size 0.254 0.3302)
			(layers "F.Cu" "F.Mask" "F.Paste")
			(net "P5E_CPU0_P2_TX_C_DP<9>")
		)
		(pad "BV4" smd circle
			(at 1.20269 -2.817368)
			(size 0.381 0.381)
			(layers "F.Cu" "F.Mask" "F.Paste")
			(net "GND")
		)
		(pad "BV13" smd circle
			(at 1.20269 -0.79629)
			(size 0.3048 0.3048)
			(layers "F.Cu" "F.Mask" "F.Paste")
			(net "GND")
		)
		(pad "BV17" smd circle
			(at 1.20269 -0.296164)
			(size 0.3048 0.3048)
			(layers "F.Cu" "F.Mask" "F.Paste")
			(net "P1V8_CPU0_RT2_1A_1D")
		)
		(pad "BV20" smd circle
			(at 1.20269 0.203708)
			(size 0.3048 0.3048)
			(layers "F.Cu" "F.Mask" "F.Paste")
			(net "P1V8_CPU0_RT2_1A")
		)
		(pad "BV22" smd circle
			(at 1.20269 0.703834)
			(size 0.3048 0.3048)
			(layers "F.Cu" "F.Mask" "F.Paste")
			(net "GND")
		)
	)
)
